# S9S_MB_2U (Grand Teton) — schematic parts with pin connectivity, parts 336–511 of 6093; source: Cadence DE-HDL packaged netlist (pstxprt.dat, pstxnet.dat, pstchip.dat)

C397  Q_CAP  47UF 4V 20% X6S  pkg C0805  page 75 : 1 = PVCCIN_CPU0 ; 2 = GND
C398  Q_CAP  47UF 4V 20% X6S  pkg C0805  page 76 : 1 = PVCCIN_CPU0 ; 2 = GND
C399  Q_CAP  22UF 4V 20% X6S  pkg C0402  page 74 : 1 = PVCCD_HV_CPU0 ; 2 = GND
C400  Q_CAP  22UF 4V 20% X6S  pkg C0402  page 74 : 1 = PVCCFA_EHV_FIVRA_CPU0 ; 2 = GND
C401  Q_CAP  22UF 4V 20% X6S  pkg C0402  page 74 : 1 = PVCCD_HV_CPU0 ; 2 = GND
C402  Q_CAP  22UF 4V 20% X6S  pkg C0402  page 74 : 1 = PVCCFA_EHV_FIVRA_CPU0 ; 2 = GND
C403  Q_CAP  22UF 4V 20% X6S  pkg C0402  page 74 : 1 = PVCCD_HV_CPU0 ; 2 = GND
C404  Q_CAP  22UF 4V 20% X6S  pkg C0402  page 74 : 1 = PVCCFA_EHV_FIVRA_CPU0 ; 2 = GND
C405  Q_CAP  22UF 4V 20% X6S  pkg C0402  page 74 : 1 = PVCCD_HV_CPU0 ; 2 = GND
C406  Q_CAP  22UF 4V 20% X6S  pkg C0402  page 74 : 1 = PVCCFA_EHV_FIVRA_CPU0 ; 2 = GND
C407  Q_CAP  22UF 4V 20% X6S  pkg C0402  page 74 : 1 = PVCCFA_EHV_FIVRA_CPU0 ; 2 = GND
C408  Q_CAP  22UF 4V 20% X6S  pkg C0402  page 74 : 1 = PVCCINFAON_CPU0 ; 2 = GND
C409  Q_CAP  22UF 4V 20% X6S  pkg C0402  page 74 : 1 = PVCCFA_EHV_FIVRA_CPU0 ; 2 = GND
C410  Q_CAP  22UF 4V 20% X6S  pkg C0402  page 74 : 1 = PVCCINFAON_CPU0 ; 2 = GND
C411  Q_CAP  22UF 4V 20% X6S  pkg C0402  page 74 : 1 = PVCCFA_EHV_FIVRA_CPU0 ; 2 = GND
C412  Q_CAP  22UF 4V 20% X6S  pkg C0402  page 74 : 1 = PVCCINFAON_CPU0 ; 2 = GND
C413  Q_CAP  22UF 4V 20% X6S  pkg C0402  page 74 : 1 = PVCCFA_EHV_FIVRA_CPU0 ; 2 = GND
C414  Q_CAP  22UF 4V 20% X6S  pkg C0402  page 74 : 1 = PVCCINFAON_CPU0 ; 2 = GND
C415  Q_CAP  22UF 4V 20% X6S  pkg C0402  page 74 : 1 = PVCCFA_EHV_FIVRA_CPU0 ; 2 = GND
C416  Q_CAP  22UF 4V 20% X6S  pkg C0402  page 74 : 1 = PVCCINFAON_CPU0 ; 2 = GND
C417  Q_CAP  22UF 4V 20% X6S  pkg C0402  page 74 : 1 = PVCCFA_EHV_FIVRA_CPU0 ; 2 = GND
C418  Q_CAP  22UF 4V 20% X6S  pkg C0402  page 74 : 1 = PVCCFA_EHV_FIVRA_CPU0 ; 2 = GND
C419  Q_CAP  22UF 4V 20% X6S  pkg C0402  page 74 : 1 = PVCCFA_EHV_CPU0 ; 2 = GND
C420  Q_CAP  22UF 4V 20% X6S  pkg C0402  page 74 : 1 = PVCCFA_EHV_CPU0 ; 2 = GND
C421  Q_CAP  22UF 4V 20% X6S  pkg C0402  page 74 : 1 = PVCCFA_EHV_CPU0 ; 2 = GND
C422  Q_CAP  22UF 4V 20% X6S  pkg C0402  page 74 : 1 = PVCCFA_EHV_CPU0 ; 2 = GND
C423  Q_CAP  22UF 4V 20% X6S  pkg C0402  page 77 : 1 = PVCCD_HV_CPU1 ; 2 = GND
C424  Q_CAP  22UF 4V 20% X6S  pkg C0402  page 77 : 1 = PVCCFA_EHV_FIVRA_CPU1 ; 2 = GND
C425  Q_CAP  22UF 4V 20% X6S  pkg C0402  page 77 : 1 = PVCCD_HV_CPU1 ; 2 = GND
C426  Q_CAP  22UF 4V 20% X6S  pkg C0402  page 77 : 1 = PVCCFA_EHV_FIVRA_CPU1 ; 2 = GND
C427  Q_CAP  22UF 4V 20% X6S  pkg C0402  page 77 : 1 = PVCCD_HV_CPU1 ; 2 = GND
C428  Q_CAP  22UF 4V 20% X6S  pkg C0402  page 77 : 1 = PVCCFA_EHV_FIVRA_CPU1 ; 2 = GND
C429  Q_CAP  22UF 4V 20% X6S  pkg C0402  page 77 : 1 = PVCCD_HV_CPU1 ; 2 = GND
C430  Q_CAP  22UF 4V 20% X6S  pkg C0402  page 77 : 1 = PVCCFA_EHV_FIVRA_CPU1 ; 2 = GND
C431  Q_CAP  22UF 4V 20% X6S  pkg C0402  page 77 : 1 = PVCCFA_EHV_FIVRA_CPU1 ; 2 = GND
C432  Q_CAP  22UF 4V 20% X6S  pkg C0402  page 77 : 1 = PVCCINFAON_CPU1 ; 2 = GND
C433  Q_CAP  22UF 4V 20% X6S  pkg C0402  page 77 : 1 = PVCCFA_EHV_FIVRA_CPU1 ; 2 = GND
C434  Q_CAP  22UF 4V 20% X6S  pkg C0402  page 77 : 1 = PVCCINFAON_CPU1 ; 2 = GND
C435  Q_CAP  22UF 4V 20% X6S  pkg C0402  page 77 : 1 = PVCCFA_EHV_FIVRA_CPU1 ; 2 = GND
C436  Q_CAP  22UF 4V 20% X6S  pkg C0402  page 77 : 1 = PVCCINFAON_CPU1 ; 2 = GND
C437  Q_CAP  22UF 4V 20% X6S  pkg C0402  page 77 : 1 = PVCCFA_EHV_FIVRA_CPU1 ; 2 = GND
C438  Q_CAP  22UF 4V 20% X6S  pkg C0402  page 77 : 1 = PVCCINFAON_CPU1 ; 2 = GND
C439  Q_CAP  22UF 4V 20% X6S  pkg C0402  page 77 : 1 = PVCCFA_EHV_FIVRA_CPU1 ; 2 = GND
C440  Q_CAP  22UF 4V 20% X6S  pkg C0402  page 77 : 1 = PVCCINFAON_CPU1 ; 2 = GND
C441  Q_CAP  22UF 4V 20% X6S  pkg C0402  page 77 : 1 = PVCCFA_EHV_FIVRA_CPU1 ; 2 = GND
C442  Q_CAP  22UF 4V 20% X6S  pkg C0402  page 77 : 1 = PVCCFA_EHV_FIVRA_CPU1 ; 2 = GND
C443  Q_CAP  22UF 4V 20% X6S  pkg C0402  page 77 : 1 = PVCCFA_EHV_CPU1 ; 2 = GND
C444  Q_CAP  22UF 4V 20% X6S  pkg C0402  page 77 : 1 = PVCCFA_EHV_CPU1 ; 2 = GND
C445  Q_CAP  22UF 4V 20% X6S  pkg C0402  page 77 : 1 = PVCCFA_EHV_CPU1 ; 2 = GND
C446  Q_CAP  22UF 4V 20% X6S  pkg C0402  page 77 : 1 = PVCCFA_EHV_CPU1 ; 2 = GND
C447  Q_CAP  47UF 4V 20% X6S  pkg C0805  page 78 : 1 = PVCCD_HV_CPU1 ; 2 = GND
C448  Q_CAP  47UF 4V 20% X6S  pkg C0805  page 78 : 1 = PVCCFA_EHV_CPU1 ; 2 = GND
C449  Q_CAP  47UF 4V 20% X6S  pkg C0805  page 78 : 1 = PVCCFA_EHV_FIVRA_CPU1 ; 2 = GND
C450  Q_CAP  47UF 4V 20% X6S  pkg C0805  page 79 : 1 = PVCCFA_EHV_FIVRA_CPU1 ; 2 = GND
C451  Q_CAP  47UF 4V 20% X6S  pkg C0805  page 78 : 1 = PVCCD_HV_CPU1 ; 2 = GND
C452  Q_CAP  47UF 4V 20% X6S  pkg C0805  page 78 : 1 = PVCCFA_EHV_CPU1 ; 2 = GND
C453  Q_CAP  47UF 4V 20% X6S  pkg C0805  page 78 : 1 = PVCCFA_EHV_FIVRA_CPU1 ; 2 = GND
C454  Q_CAP  47UF 4V 20% X6S  pkg C0805  page 79 : 1 = PVCCFA_EHV_FIVRA_CPU1 ; 2 = GND
C455  Q_CAP  47UF 4V 20% X6S  pkg C0805  page 79 : 1 = PVCCD_HV_CPU1 ; 2 = GND
C456  Q_CAP  47UF 4V 20% X6S  pkg C0805  page 79 : 1 = PVCCFA_EHV_CPU1 ; 2 = GND
C457  Q_CAP  47UF 4V 20% X6S  pkg C0805  page 78 : 1 = PVCCFA_EHV_FIVRA_CPU1 ; 2 = GND
C458  Q_CAP  47UF 4V 20% X6S  pkg C0805  page 79 : 1 = PVCCFA_EHV_FIVRA_CPU1 ; 2 = GND
C459  Q_CAP  47UF 4V 20% X6S  pkg C0805  page 79 : 1 = PVCCD_HV_CPU1 ; 2 = GND
C460  Q_CAP  47UF 4V 20% X6S  pkg C0805  page 79 : 1 = PVCCFA_EHV_CPU1 ; 2 = GND
C461  Q_CAP  47UF 4V 20% X6S  pkg C0805  page 78 : 1 = PVCCFA_EHV_FIVRA_CPU1 ; 2 = GND
C462  Q_CAP  47UF 4V 20% X6S  pkg C0805  page 79 : 1 = PVCCFA_EHV_FIVRA_CPU1 ; 2 = GND
C463  Q_CAP  47UF 4V 20% X6S  pkg C0805  page 79 : 1 = PVCCD_HV_CPU1 ; 2 = GND
C464  Q_CAP  47UF 4V 20% X6S  pkg C0805  page 79 : 1 = PVCCFA_EHV_CPU1 ; 2 = GND
C465  Q_CAP  47UF 2.5V 20% X6S  pkg C0603  page 78 : 1 = PVCCFA_EHV_FIVRA_CPU1 ; 2 = GND
C466  Q_CAP  47UF 4V 20% X6S  pkg C0805  page 79 : 1 = PVCCFA_EHV_FIVRA_CPU1 ; 2 = GND
C467  Q_CAP  47UF 4V 20% X6S  pkg C0805  page 79 : 1 = PVCCD_HV_CPU1 ; 2 = GND
C468  Q_CAP  47UF 4V 20% X6S  pkg C0805  page 79 : 1 = PVCCFA_EHV_CPU1 ; 2 = GND
C470  Q_CAP  47UF 4V 20% X6S  pkg C0805  page 79 : 1 = PVCCFA_EHV_FIVRA_CPU1 ; 2 = GND
C471  Q_CAP  47UF 4V 20% X6S  pkg C0805  page 78 : 1 = PVCCD_HV_CPU1 ; 2 = GND
C472  Q_CAP  47UF 2.5V 20% X6S  pkg C0603  page 79 : 1 = PVCCFA_EHV_CPU1 ; 2 = GND
C473  Q_CAP  47UF 4V 20% X6S  pkg C0805  page 79 : 1 = PVCCFA_EHV_FIVRA_CPU1 ; 2 = GND
C474  Q_CAP  47UF 4V 20% X6S  pkg C0805  page 78 : 1 = PVCCD_HV_CPU1 ; 2 = GND
C475  Q_CAP  47UF 2.5V 20% X6S  pkg C0603  page 79 : 1 = PVCCFA_EHV_CPU1 ; 2 = GND
C476  Q_CAP  47UF 4V 20% X6S  pkg C0805  page 79 : 1 = PVCCFA_EHV_FIVRA_CPU1 ; 2 = GND
C477  Q_CAP  47UF 4V 20% X6S  pkg C0805  page 79 : 1 = PVCCFA_EHV_FIVRA_CPU1 ; 2 = GND
C478  Q_CAP  47UF 4V 20% X6S  pkg C0805  page 78 : 1 = PVCCINFAON_CPU1 ; 2 = GND
C479  Q_CAP  47UF 4V 20% X6S  pkg C0805  page 79 : 1 = PVCCFA_EHV_FIVRA_CPU1 ; 2 = GND
C481  Q_CAP  47UF 4V 20% X6S  pkg C0805  page 79 : 1 = PVCCINFAON_CPU1 ; 2 = GND
C482  Q_CAP  47UF 4V 20% X6S  pkg C0805  page 79 : 1 = PVCCFA_EHV_FIVRA_CPU1 ; 2 = GND
C483  Q_CAP  47UF 4V 20% X6S  pkg C0805  page 78 : 1 = PVCCIN_CPU1 ; 2 = GND
C484  Q_CAP  47UF 4V 20% X6S  pkg C0805  page 79 : 1 = PVCCINFAON_CPU1 ; 2 = GND
C485  Q_CAP  47UF 4V 20% X6S  pkg C0805  page 79 : 1 = PVCCFA_EHV_FIVRA_CPU1 ; 2 = GND
C486  Q_CAP  47UF 4V 20% X6S  pkg C0805  page 79 : 1 = PVCCINFAON_CPU1 ; 2 = GND
C487  Q_CAP  47UF 4V 20% X6S  pkg C0805  page 79 : 1 = PVCCINFAON_CPU1 ; 2 = GND
C488  Q_CAP  47UF 2.5V 20% X6S  pkg C0603  page 78 : 1 = PVCCINFAON_CPU1 ; 2 = GND
C489  Q_CAP  47UF 2.5V 20% X6S  pkg C0603  page 78 : 1 = PVCCINFAON_CPU1 ; 2 = GND
C490  Q_CAP  22UF 4V 20% X6S  pkg C0402  page 78 : 1 = PVCCINFAON_CPU1 ; 2 = GND
C491  Q_CAP  47UF 4V 20% X6S  pkg C0805  page 75 : 1 = PVCCD_HV_CPU0 ; 2 = GND
C492  Q_CAP  47UF 4V 20% X6S  pkg C0805  page 75 : 1 = PVCCFA_EHV_CPU0 ; 2 = GND
C493  Q_CAP  47UF 4V 20% X6S  pkg C0805  page 75 : 1 = PVCCFA_EHV_FIVRA_CPU0 ; 2 = GND
C494  Q_CAP  47UF 4V 20% X6S  pkg C0805  page 76 : 1 = PVCCFA_EHV_FIVRA_CPU0 ; 2 = GND
C495  Q_CAP  47UF 4V 20% X6S  pkg C0805  page 75 : 1 = PVCCD_HV_CPU0 ; 2 = GND
C496  Q_CAP  47UF 4V 20% X6S  pkg C0805  page 75 : 1 = PVCCFA_EHV_CPU0 ; 2 = GND
C497  Q_CAP  47UF 4V 20% X6S  pkg C0805  page 75 : 1 = PVCCFA_EHV_FIVRA_CPU0 ; 2 = GND
C498  Q_CAP  47UF 4V 20% X6S  pkg C0805  page 76 : 1 = PVCCFA_EHV_FIVRA_CPU0 ; 2 = GND
C499  Q_CAP  47UF 4V 20% X6S  pkg C0805  page 76 : 1 = PVCCD_HV_CPU0 ; 2 = GND
C500  Q_CAP  47UF 4V 20% X6S  pkg C0805  page 76 : 1 = PVCCFA_EHV_CPU0 ; 2 = GND
C501  Q_CAP  47UF 4V 20% X6S  pkg C0805  page 75 : 1 = PVCCFA_EHV_FIVRA_CPU0 ; 2 = GND
C502  Q_CAP  47UF 4V 20% X6S  pkg C0805  page 76 : 1 = PVCCFA_EHV_FIVRA_CPU0 ; 2 = GND
C503  Q_CAP  47UF 4V 20% X6S  pkg C0805  page 76 : 1 = PVCCD_HV_CPU0 ; 2 = GND
C504  Q_CAP  47UF 4V 20% X6S  pkg C0805  page 76 : 1 = PVCCFA_EHV_CPU0 ; 2 = GND
C505  Q_CAP  47UF 4V 20% X6S  pkg C0805  page 75 : 1 = PVCCFA_EHV_FIVRA_CPU0 ; 2 = GND
C506  Q_CAP  47UF 4V 20% X6S  pkg C0805  page 76 : 1 = PVCCFA_EHV_FIVRA_CPU0 ; 2 = GND
C507  Q_CAP  47UF 4V 20% X6S  pkg C0805  page 76 : 1 = PVCCD_HV_CPU0 ; 2 = GND
C508  Q_CAP  47UF 4V 20% X6S  pkg C0805  page 76 : 1 = PVCCFA_EHV_CPU0 ; 2 = GND
C509  Q_CAP  47UF 2.5V 20% X6S  pkg C0603  page 75 : 1 = PVCCFA_EHV_FIVRA_CPU0 ; 2 = GND
C510  Q_CAP  47UF 4V 20% X6S  pkg C0805  page 76 : 1 = PVCCFA_EHV_FIVRA_CPU0 ; 2 = GND
C511  Q_CAP  47UF 4V 20% X6S  pkg C0805  page 76 : 1 = PVCCD_HV_CPU0 ; 2 = GND
C512  Q_CAP  47UF 4V 20% X6S  pkg C0805  page 76 : 1 = PVCCFA_EHV_CPU0 ; 2 = GND
C513  Q_CAP  22UF 16V 20% X6S  pkg C0805  page 257 : 1 = PGPPA_AUX ; 2 = GND
C514  Q_CAP  47UF 4V 20% X6S  pkg C0805  page 76 : 1 = PVCCFA_EHV_FIVRA_CPU0 ; 2 = GND
C515  Q_CAP  47UF 4V 20% X6S  pkg C0805  page 75 : 1 = PVCCD_HV_CPU0 ; 2 = GND
C516  Q_CAP  47UF 2.5V 20% X6S  pkg C0603  page 76 : 1 = PVCCFA_EHV_CPU0 ; 2 = GND
C517  Q_CAP  47UF 4V 20% X6S  pkg C0805  page 76 : 1 = PVCCFA_EHV_FIVRA_CPU0 ; 2 = GND
C518  Q_CAP  47UF 4V 20% X6S  pkg C0805  page 75 : 1 = PVCCD_HV_CPU0 ; 2 = GND
C519  Q_CAP  47UF 2.5V 20% X6S  pkg C0603  page 76 : 1 = PVCCFA_EHV_CPU0 ; 2 = GND
C520  Q_CAP  47UF 4V 20% X6S  pkg C0805  page 76 : 1 = PVCCFA_EHV_FIVRA_CPU0 ; 2 = GND
C521  Q_CAP  47UF 4V 20% X6S  pkg C0805  page 76 : 1 = PVCCFA_EHV_FIVRA_CPU0 ; 2 = GND
C522  Q_CAP  47UF 4V 20% X6S  pkg C0805  page 75 : 1 = PVCCINFAON_CPU0 ; 2 = GND
C523  Q_CAP  47UF 4V 20% X6S  pkg C0805  page 76 : 1 = PVCCFA_EHV_FIVRA_CPU0 ; 2 = GND
C525  Q_CAP  47UF 4V 20% X6S  pkg C0805  page 76 : 1 = PVCCINFAON_CPU0 ; 2 = GND
C526  Q_CAP  47UF 4V 20% X6S  pkg C0805  page 76 : 1 = PVCCFA_EHV_FIVRA_CPU0 ; 2 = GND
C527  Q_CAP  47UF 4V 20% X6S  pkg C0805  page 75 : 1 = PVCCIN_CPU0 ; 2 = GND
C528  Q_CAP  47UF 4V 20% X6S  pkg C0805  page 76 : 1 = PVCCINFAON_CPU0 ; 2 = GND
C529  Q_CAP  47UF 4V 20% X6S  pkg C0805  page 76 : 1 = PVCCFA_EHV_FIVRA_CPU0 ; 2 = GND
C530  Q_CAP  47UF 4V 20% X6S  pkg C0805  page 76 : 1 = PVCCINFAON_CPU0 ; 2 = GND
C531  Q_CAP  47UF 4V 20% X6S  pkg C0805  page 76 : 1 = PVCCINFAON_CPU0 ; 2 = GND
C532  Q_CAP  47UF 2.5V 20% X6S  pkg C0603  page 75 : 1 = PVCCINFAON_CPU0 ; 2 = GND
C533  Q_CAP  47UF 2.5V 20% X6S  pkg C0603  page 75 : 1 = PVCCINFAON_CPU0 ; 2 = GND
C534  Q_CAP  22UF 4V 20% X6S  pkg C0402  page 75 : 1 = PVCCINFAON_CPU0 ; 2 = GND
C535  Q_CAP  22UF 16V 20% X6S  pkg C0805  page 257 : 1 = PGPPA_AUX ; 2 = GND
C537  Q_CAP  0.1UF 25V 10% X7R  pkg 0402  page 230 : 1 = P3V3_AUX ; 2 = GND
C538  Q_CAP  0.1UF 25V 10% X7R  pkg 0402  page 229 : 1 = P3V3_AUX ; 2 = GND
C539  Q_CAP  0.1UF 25V 10% X7R  pkg 0402  page 133 : 1 = P3V3_AUX ; 2 = GND
C540  Q_CAP  0.1UF 25V 10% X7R  pkg 0402  page 133 : 1 = P3V3_AUX ; 2 = GND
C541  Q_CAP  1UF 25V 10% X6S  pkg C0402  page 133 : 1 = P3V3_AUX ; 2 = GND
C542  Q_CAP  1UF 25V 10% X6S  pkg C0402  page 133 : 1 = P3V3_AUX ; 2 = GND
C543  Q_CAP  0.1UF 25V 10% X7R  pkg 0402  page 133 : 1 = P3V3_AUX ; 2 = GND
C544  Q_CAP  0.1UF 25V 10% X7R  pkg 0402  page 133 : 1 = P3V3_AUX ; 2 = GND
C545  Q_CAP  1UF 25V 10% X6S  pkg C0402  page 132 : 1 = P3V3_AUX ; 2 = GND
C546  Q_CAP  1UF 25V 10% X6S  pkg C0402  page 132 : 1 = P3V3_AUX ; 2 = GND
C547  Q_CAP  1UF 25V 10% X6S  pkg C0402  page 131 : 1 = P1V05_PCH_AUX ; 2 = GND
C548  Q_CAP  0.1UF 25V 10% X7R  pkg 0402  page 131 : 1 = JTAG_DBP_POWER_BTN_N ; 2 = GND
C549  Q_CAP  0.1UF 25V 10% X7R  pkg 0402  page 131 : 1 = JTAG_RST_DBP_RST_CO_N ; 2 = GND
C550  Q_CAP  1UF 25V 10% X6S  pkg C0402  page 131 : 1 = P1V8_PCH_AUX ; 2 = GND
C551  Q_CAP  1UF 25V 10% X6S  pkg C0402  page 131 : 1 = P3V3_AUX ; 2 = GND
C552  Q_CAP  0.1UF 25V 10% X7R  pkg 0402  page 131 : 1 = FM_CPU_FBRK_DEBUG_N ; 2 = GND
C554  Q_CAP  0.1UF 25V 10% X7R  pkg 0402  page 221 : 1 = P3V3_AUX_BMC_D ; 2 = GND
C559  Q_CAP  0.1UF 25V 10% X7R  pkg 0402  page 235 : 1 = PVNN_TERM_CPU0 ; 2 = GND
C560  Q_CAP  0.1UF 25V 10% X7R  pkg 0402  page 235 : 1 = PVNN_TERM_CPU1 ; 2 = GND
C561  Q_CAP  0.1UF 25V 10% X7R  pkg 0402  page 235 : 1 = P3V3_AUX ; 2 = GND
C562  Q_CAP  0.1UF 25V 10% X7R  pkg 0402  page 235 : 1 = P3V3_AUX ; 2 = GND
C563  Q_CAP  10UF 25V 10% X6S  pkg C0805  page 221 : 1 = P3V3_AUX_BMC_D ; 2 = GND
C567  Q_CAP  0.1UF 25V 10% X7R  pkg 0402  page 236 : 1 = PVNN_TERM_CPU0 ; 2 = GND
C568  Q_CAP  0.1UF 25V 10% X7R  pkg 0402  page 236 : 1 = PVNN_TERM_CPU1 ; 2 = GND
C569  Q_CAP  0.1UF 25V 10% X7R  pkg 0402  page 236 : 1 = P3V3_AUX ; 2 = GND
C570  Q_CAP  0.1UF 25V 10% X7R  pkg 0402  page 236 : 1 = P3V3_AUX ; 2 = GND
C578  Q_CAP  0.1UF 25V 10% X7R  pkg 0402  page 158 : 1 = P3V3_AUX ; 2 = GND
C579  Q_CAP  0.1UF 25V 10% X7R  pkg 0402  page 158 : 1 = P3V3_AUX ; 2 = GND
C580  Q_CAP  0.1UF 25V 10% X7R  pkg 0402  page 158 : 1 = P3V3_OCP_SFF ; 2 = GND
C581  Q_CAP  0.1UF 25V 10% X7R  pkg 0402  page 158 : 1 = P3V3_AUX ; 2 = GND
C590  Q_CAP  22UF 4V 20% X6S  pkg C0402  page 74 : 1 = PVNN_MAIN_CPU0 ; 2 = GND
C592  Q_CAP  0.1UF 25V 10% X7R  pkg 0402  page 156 : 1 = P3V3_AUX ; 2 = GND
C593  Q_CAP  0.1UF 25V 10% X7R  pkg 0402  page 156 : 1 = P3V3_AUX ; 2 = GND
C605  Q_CAP  1UF 25V 10% X6S  pkg C0402  page 202 : 1 = PGPPA_AUX ; 2 = GND
C606  Q_CAP  1UF 25V 10% X6S  pkg C0402  page 202 : 1 = PGPPA_AUX ; 2 = GND
C607  Q_CAP  0.1UF 25V 10% X7R  pkg 0402  page 202 : 1 = PGPPA_AUX ; 2 = GND
C608  Q_CAP  0.1UF 25V 10% X7R  pkg 0402  page 202 : 1 = PGPPA_AUX ; 2 = GND
C609  Q_CAP  0.1UF 25V 10% X7R  pkg 0402  page 179 : 1 = RTC_EXT_CAP ; 2 = GND
C610  Q_CAP  1UF 25V 10% X6S  pkg C0402  page 185 : 1 = RST_SRTCRST_N ; 2 = GND
C611  Q_CAP  1UF 25V 10% X6S  pkg C0402  page 185 : 1 = P3V3_RTC_AUX ; 2 = GND
